# S9S_MB_2U (Grand Teton) — schematic netlist excerpt (pin names and nets, part order shuffled) for the footprints in the layout excerpt that follows; sources: Cadence DE-HDL packaged netlist, KiCad conversion of 03242023_DA0F0TMBIJ0_F0T_Motherboard_J_brd_V01_OCP.brd

R1907  Q_RES  1K 1% CHIP  pkg 0402LF  page 156 : A = P3V3_AUX ; B = OCP_SFF_PRSNT1_R_N
C978  Q_CAP  10UF 6.3V 20% X6S  pkg C0402  page 74 : A = PVCCIN_CPU0 ; B = GND

(kicad_pcb
	(version 20260206)
	(generator "pcbnew")
	(generator_version "10.0")
	(general
		(thickness 1.6)
		(legacy_teardrops no)
	)
	(paper "A4")
	(title_block
		(title "03242023_DA0F0TMBIJ0_F0T_Motherboard_J_brd_V01_OCP.brd")
		(comment 1 "Grand Teton / footprints 3827-3828 of 6105")
	)
	(layers
		(0 "F.Cu" signal "TOP")
		(4 "In1.Cu" signal "GND")
		(6 "In2.Cu" signal "IN1")
		(8 "In3.Cu" signal "GND1")
		(10 "In4.Cu" signal "IN2")
		(12 "In5.Cu" signal "GND2")
		(14 "In6.Cu" signal "IN3")
		(16 "In7.Cu" signal "GND3")
		(18 "In8.Cu" signal "VCC")
		(20 "In9.Cu" signal "VCC1")
		(22 "In10.Cu" signal "GND4")
		(24 "In11.Cu" signal "IN4")
		(26 "In12.Cu" signal "GND5")
		(28 "In13.Cu" signal "IN5")
		(30 "In14.Cu" signal "GND6")
		(32 "In15.Cu" signal "IN6")
		(34 "In16.Cu" signal "GND7")
		(2 "B.Cu" signal "BOTTOM")
		(9 "F.Adhes" user "F.Adhesive")
		(11 "B.Adhes" user "B.Adhesive")
		(13 "F.Paste" user "Package Geometry/Pastemask Top")
		(15 "B.Paste" user "Package Geometry/Pastemask Bottom")
		(5 "F.SilkS" user "Ref Des/Silkscreen Top")
		(7 "B.SilkS" user "Ref Des/Silkscreen Bottom")
		(1 "F.Mask" user "Board Geometry/Soldermask Top")
		(3 "B.Mask" user "Board Geometry/Soldermask Bottom")
		(17 "Dwgs.User" user "User.Drawings")
		(19 "Cmts.User" user "User.Comments")
		(21 "Eco1.User" user "User.Eco1")
		(23 "Eco2.User" user "User.Eco2")
		(25 "Edge.Cuts" user "Board Geometry/Outline")
		(27 "Margin" user)
		(31 "F.CrtYd" user "Package Geometry/Place Bound Top")
		(29 "B.CrtYd" user "Package Geometry/Place Bound Bottom")
		(35 "F.Fab" user "Ref Des/Assembly Top")
		(33 "B.Fab" user "Ref Des/Assembly Bottom")
	)
	(footprint ""
		(layer "F.Cu")
		(at 355.216714 -256.654046 -90)
		(property "Reference" "C978"
			(at 0 0 270)
			(layer "F.SilkS")
			(hide yes)
			(effects
				(font
					(size 1.27 1.27)
				)
			)
		)
		(property "Value" ""
			(at 0 0 270)
			(layer "F.Fab")
			(effects
				(font
					(size 1.27 1.27)
				)
			)
		)
		(duplicate_pad_numbers_are_jumpers no)
		(fp_line
			(start -0.7874 0.4064)
			(end -0.7874 -0.4064)
			(stroke
				(width 0.1524)
				(type default)
			)
			(layer "F.SilkS")
		)
		(fp_line
			(start 0.7874 0.4064)
			(end -0.7874 0.4064)
			(stroke
				(width 0.1524)
				(type default)
			)
			(layer "F.SilkS")
		)
		(fp_line
			(start -0.7874 -0.4064)
			(end 0.7874 -0.4064)
			(stroke
				(width 0.1524)
				(type default)
			)
			(layer "F.SilkS")
		)
		(fp_line
			(start 0.7874 -0.4064)
			(end 0.7874 0.4064)
			(stroke
				(width 0.1524)
				(type default)
			)
			(layer "F.SilkS")
		)
		(fp_line
			(start -0.67945 0.3048)
			(end -0.67945 -0.305054)
			(stroke
				(width 0.1)
				(type default)
			)
			(layer "F.Fab")
		)
		(fp_line
			(start -0.12065 0.3048)
			(end -0.67945 0.3048)
			(stroke
				(width 0.1)
				(type default)
			)
			(layer "F.Fab")
		)
		(fp_line
			(start 0.120396 0.3048)
			(end 0.120396 0.2794)
			(stroke
				(width 0.1)
				(type default)
			)
			(layer "F.Fab")
		)
		(fp_line
			(start 0.67945 0.3048)
			(end 0.120396 0.3048)
			(stroke
				(width 0.1)
				(type default)
			)
			(layer "F.Fab")
		)
		(fp_line
			(start -0.12065 0.2794)
			(end -0.12065 0.3048)
			(stroke
				(width 0.1)
				(type default)
			)
			(layer "F.Fab")
		)
		(fp_line
			(start 0.120396 0.2794)
			(end -0.12065 0.2794)
			(stroke
				(width 0.1)
				(type default)
			)
			(layer "F.Fab")
		)
		(fp_line
			(start -0.12065 -0.2794)
			(end 0.12065 -0.2794)
			(stroke
				(width 0.1)
				(type default)
			)
			(layer "F.Fab")
		)
		(fp_line
			(start 0.12065 -0.2794)
			(end 0.12065 -0.3048)
			(stroke
				(width 0.1)
				(type default)
			)
			(layer "F.Fab")
		)
		(fp_line
			(start 0.12065 -0.3048)
			(end 0.67945 -0.3048)
			(stroke
				(width 0.1)
				(type default)
			)
			(layer "F.Fab")
		)
		(fp_line
			(start 0.67945 -0.3048)
			(end 0.67945 0.3048)
			(stroke
				(width 0.1)
				(type default)
			)
			(layer "F.Fab")
		)
		(fp_line
			(start -0.67945 -0.305054)
			(end -0.12065 -0.305054)
			(stroke
				(width 0.1)
				(type default)
			)
			(layer "F.Fab")
		)
		(fp_line
			(start -0.12065 -0.305054)
			(end -0.12065 -0.2794)
			(stroke
				(width 0.1)
				(type default)
			)
			(layer "F.Fab")
		)
		(pad "1" smd circle
			(at -0.40005 0 270)
			(size 0 0)
			(layers "F.Cu" "F.Mask" "F.Paste")
			(net "PVCCIN_CPU0")
		)
		(pad "2" smd circle
			(at 0.40005 0 270)
			(size 0 0)
			(layers "F.Cu" "F.Mask" "F.Paste")
			(net "GND")
		)
	)
	(footprint ""
		(layer "F.Cu")
		(at 453.719946 -106.408728)
		(property "Reference" "R1907"
			(at 0 0 0)
			(layer "F.SilkS")
			(hide yes)
			(effects
				(font
					(size 1.27 1.27)
				)
			)
		)
		(property "Value" ""
			(at 0 0 0)
			(layer "F.Fab")
			(effects
				(font
					(size 1.27 1.27)
				)
			)
		)
		(duplicate_pad_numbers_are_jumpers no)
		(fp_line
			(start -0.7874 -0.4064)
			(end 0.7874 -0.4064)
			(stroke
				(width 0.1524)
				(type default)
			)
			(layer "F.SilkS")
		)
		(fp_line
			(start -0.7874 0.4064)
			(end -0.7874 -0.4064)
			(stroke
				(width 0.1524)
				(type default)
			)
			(layer "F.SilkS")
		)
		(fp_line
			(start 0.7874 -0.4064)
			(end 0.7874 0.4064)
			(stroke
				(width 0.1524)
				(type default)
			)
			(layer "F.SilkS")
		)
		(fp_line
			(start 0.7874 0.4064)
			(end -0.7874 0.4064)
			(stroke
				(width 0.1524)
				(type default)
			)
			(layer "F.SilkS")
		)
		(fp_line
			(start -0.67945 -0.305054)
			(end -0.12065 -0.305054)
			(stroke
				(width 0.1)
				(type default)
			)
			(layer "F.Fab")
		)
		(fp_line
			(start -0.67945 0.3048)
			(end -0.67945 -0.305054)
			(stroke
				(width 0.1)
				(type default)
			)
			(layer "F.Fab")
		)
		(fp_line
			(start -0.12065 -0.305054)
			(end -0.12065 -0.2794)
			(stroke
				(width 0.1)
				(type default)
			)
			(layer "F.Fab")
		)
		(fp_line
			(start -0.12065 -0.2794)
			(end 0.12065 -0.2794)
			(stroke
				(width 0.1)
				(type default)
			)
			(layer "F.Fab")
		)
		(fp_line
			(start -0.12065 0.2794)
			(end -0.12065 0.3048)
			(stroke
				(width 0.1)
				(type default)
			)
			(layer "F.Fab")
		)
		(fp_line
			(start -0.12065 0.3048)
			(end -0.67945 0.3048)
			(stroke
				(width 0.1)
				(type default)
			)
			(layer "F.Fab")
		)
		(fp_line
			(start 0.120396 0.2794)
			(end -0.12065 0.2794)
			(stroke
				(width 0.1)
				(type default)
			)
			(layer "F.Fab")
		)
		(fp_line
			(start 0.120396 0.3048)
			(end 0.120396 0.2794)
			(stroke
				(width 0.1)
				(type default)
			)
			(layer "F.Fab")
		)
		(fp_line
			(start 0.12065 -0.3048)
			(end 0.67945 -0.3048)
			(stroke
				(width 0.1)
				(type default)
			)
			(layer "F.Fab")
		)
		(fp_line
			(start 0.12065 -0.2794)
			(end 0.12065 -0.3048)
			(stroke
				(width 0.1)
				(type default)
			)
			(layer "F.Fab")
		)
		(fp_line
			(start 0.67945 -0.3048)
			(end 0.67945 0.3048)
			(stroke
				(width 0.1)
				(type default)
			)
			(layer "F.Fab")
		)
		(fp_line
			(start 0.67945 0.3048)
			(end 0.120396 0.3048)
			(stroke
				(width 0.1)
				(type default)
			)
			(layer "F.Fab")
		)
		(pad "1" smd circle
			(at -0.40005 0)
			(size 0 0)
			(layers "F.Cu" "F.Mask" "F.Paste")
			(net "P3V3_AUX")
		)
		(pad "2" smd circle
			(at 0.40005 0)
			(size 0 0)
			(layers "F.Cu" "F.Mask" "F.Paste")
			(net "OCP_SFF_PRSNT1_R_N")
		)
	)
)
